# T6G (Grand Teton) — schematic netlist excerpt (pin names and nets, part order shuffled) for the footprints in the layout excerpt that follows; sources: Cadence DE-HDL packaged netlist, KiCad conversion of 04192023_DAF0TMB3IC0_F0TG_MB_C_brd_V02_OCP.brd

C639  Q_CAP  0.1UF 25V 10% X7R  pkg 0402  page 132 : A = P3V3_AUX ; B = GND
C1823  Q_CAP  0.1UF 25V 10% X7R  pkg 0402  page 139 : A = P3V3_AUX ; B = GND

(kicad_pcb
	(version 20260206)
	(generator "pcbnew")
	(generator_version "10.0")
	(general
		(thickness 1.6)
		(legacy_teardrops no)
	)
	(paper "A4")
	(title_block
		(title "04192023_DAF0TMB3IC0_F0TG_MB_C_brd_V02_OCP.brd")
		(comment 1 "Grand Teton / footprints 4496-4497 of 8354")
	)
	(layers
		(0 "F.Cu" signal "TOP")
		(4 "In1.Cu" signal "GND")
		(6 "In2.Cu" signal "IN1")
		(8 "In3.Cu" signal "GND1")
		(10 "In4.Cu" signal "IN2")
		(12 "In5.Cu" signal "GND2")
		(14 "In6.Cu" signal "IN3")
		(16 "In7.Cu" signal "GND3")
		(18 "In8.Cu" signal "VCC")
		(20 "In9.Cu" signal "VCC1")
		(22 "In10.Cu" signal "GND4")
		(24 "In11.Cu" signal "IN4")
		(26 "In12.Cu" signal "GND5")
		(28 "In13.Cu" signal "IN5")
		(30 "In14.Cu" signal "GND6")
		(32 "In15.Cu" signal "IN6")
		(34 "In16.Cu" signal "GND7")
		(2 "B.Cu" signal "BOTTOM")
		(9 "F.Adhes" user "F.Adhesive")
		(11 "B.Adhes" user "B.Adhesive")
		(13 "F.Paste" user "Package Geometry/Pastemask Top")
		(15 "B.Paste" user "Package Geometry/Pastemask Bottom")
		(5 "F.SilkS" user "Ref Des/Silkscreen Top")
		(7 "B.SilkS" user "Ref Des/Silkscreen Bottom")
		(1 "F.Mask" user "Board Geometry/Soldermask Top")
		(3 "B.Mask" user "Board Geometry/Soldermask Bottom")
		(17 "Dwgs.User" user "User.Drawings")
		(19 "Cmts.User" user "User.Comments")
		(21 "Eco1.User" user "User.Eco1")
		(23 "Eco2.User" user "User.Eco2")
		(25 "Edge.Cuts" user "Board Geometry/Outline")
		(27 "Margin" user)
		(31 "F.CrtYd" user "Package Geometry/Place Bound Top")
		(29 "B.CrtYd" user "Package Geometry/Place Bound Bottom")
		(35 "F.Fab" user "Ref Des/Assembly Top")
		(33 "B.Fab" user "Ref Des/Assembly Bottom")
	)
	(footprint ""
		(layer "F.Cu")
		(at 461.916526 -100.470208)
		(property "Reference" "C639"
			(at 0 0 0)
			(layer "F.SilkS")
			(hide yes)
			(effects
				(font
					(size 1.27 1.27)
				)
			)
		)
		(property "Value" ""
			(at 0 0 0)
			(layer "F.Fab")
			(effects
				(font
					(size 1.27 1.27)
				)
			)
		)
		(duplicate_pad_numbers_are_jumpers no)
		(fp_line
			(start -0.7874 -0.4064)
			(end 0.7874 -0.4064)
			(stroke
				(width 0.1524)
				(type default)
			)
			(layer "F.SilkS")
		)
		(fp_line
			(start -0.7874 0.4064)
			(end -0.7874 -0.4064)
			(stroke
				(width 0.1524)
				(type default)
			)
			(layer "F.SilkS")
		)
		(fp_line
			(start 0.7874 -0.4064)
			(end 0.7874 0.4064)
			(stroke
				(width 0.1524)
				(type default)
			)
			(layer "F.SilkS")
		)
		(fp_line
			(start 0.7874 0.4064)
			(end -0.7874 0.4064)
			(stroke
				(width 0.1524)
				(type default)
			)
			(layer "F.SilkS")
		)
		(fp_line
			(start -0.67945 -0.305054)
			(end -0.12065 -0.305054)
			(stroke
				(width 0.1)
				(type default)
			)
			(layer "F.Fab")
		)
		(fp_line
			(start -0.67945 0.3048)
			(end -0.67945 -0.305054)
			(stroke
				(width 0.1)
				(type default)
			)
			(layer "F.Fab")
		)
		(fp_line
			(start -0.12065 -0.305054)
			(end -0.12065 -0.2794)
			(stroke
				(width 0.1)
				(type default)
			)
			(layer "F.Fab")
		)
		(fp_line
			(start -0.12065 -0.2794)
			(end 0.12065 -0.2794)
			(stroke
				(width 0.1)
				(type default)
			)
			(layer "F.Fab")
		)
		(fp_line
			(start -0.12065 0.2794)
			(end -0.12065 0.3048)
			(stroke
				(width 0.1)
				(type default)
			)
			(layer "F.Fab")
		)
		(fp_line
			(start -0.12065 0.3048)
			(end -0.67945 0.3048)
			(stroke
				(width 0.1)
				(type default)
			)
			(layer "F.Fab")
		)
		(fp_line
			(start 0.120396 0.2794)
			(end -0.12065 0.2794)
			(stroke
				(width 0.1)
				(type default)
			)
			(layer "F.Fab")
		)
		(fp_line
			(start 0.120396 0.3048)
			(end 0.120396 0.2794)
			(stroke
				(width 0.1)
				(type default)
			)
			(layer "F.Fab")
		)
		(fp_line
			(start 0.12065 -0.3048)
			(end 0.67945 -0.3048)
			(stroke
				(width 0.1)
				(type default)
			)
			(layer "F.Fab")
		)
		(fp_line
			(start 0.12065 -0.2794)
			(end 0.12065 -0.3048)
			(stroke
				(width 0.1)
				(type default)
			)
			(layer "F.Fab")
		)
		(fp_line
			(start 0.67945 -0.3048)
			(end 0.67945 0.3048)
			(stroke
				(width 0.1)
				(type default)
			)
			(layer "F.Fab")
		)
		(fp_line
			(start 0.67945 0.3048)
			(end 0.120396 0.3048)
			(stroke
				(width 0.1)
				(type default)
			)
			(layer "F.Fab")
		)
		(pad "1" smd circle
			(at -0.40005 0)
			(size 0 0)
			(layers "F.Cu" "F.Mask" "F.Paste")
			(net "P3V3_AUX")
		)
		(pad "2" smd circle
			(at 0.40005 0)
			(size 0 0)
			(layers "F.Cu" "F.Mask" "F.Paste")
			(net "GND")
		)
	)
	(footprint ""
		(layer "F.Cu")
		(at 256.210308 -110.090204)
		(property "Reference" "C1823"
			(at 0 0 0)
			(layer "F.SilkS")
			(hide yes)
			(effects
				(font
					(size 1.27 1.27)
				)
			)
		)
		(property "Value" ""
			(at 0 0 0)
			(layer "F.Fab")
			(effects
				(font
					(size 1.27 1.27)
				)
			)
		)
		(duplicate_pad_numbers_are_jumpers no)
		(fp_line
			(start -0.7874 -0.4064)
			(end 0.7874 -0.4064)
			(stroke
				(width 0.1524)
				(type default)
			)
			(layer "F.SilkS")
		)
		(fp_line
			(start -0.7874 0.4064)
			(end -0.7874 -0.4064)
			(stroke
				(width 0.1524)
				(type default)
			)
			(layer "F.SilkS")
		)
		(fp_line
			(start 0.7874 -0.4064)
			(end 0.7874 0.4064)
			(stroke
				(width 0.1524)
				(type default)
			)
			(layer "F.SilkS")
		)
		(fp_line
			(start 0.7874 0.4064)
			(end -0.7874 0.4064)
			(stroke
				(width 0.1524)
				(type default)
			)
			(layer "F.SilkS")
		)
		(fp_line
			(start -0.67945 -0.305054)
			(end -0.12065 -0.305054)
			(stroke
				(width 0.1)
				(type default)
			)
			(layer "F.Fab")
		)
		(fp_line
			(start -0.67945 0.3048)
			(end -0.67945 -0.305054)
			(stroke
				(width 0.1)
				(type default)
			)
			(layer "F.Fab")
		)
		(fp_line
			(start -0.12065 -0.305054)
			(end -0.12065 -0.2794)
			(stroke
				(width 0.1)
				(type default)
			)
			(layer "F.Fab")
		)
		(fp_line
			(start -0.12065 -0.2794)
			(end 0.12065 -0.2794)
			(stroke
				(width 0.1)
				(type default)
			)
			(layer "F.Fab")
		)
		(fp_line
			(start -0.12065 0.2794)
			(end -0.12065 0.3048)
			(stroke
				(width 0.1)
				(type default)
			)
			(layer "F.Fab")
		)
		(fp_line
			(start -0.12065 0.3048)
			(end -0.67945 0.3048)
			(stroke
				(width 0.1)
				(type default)
			)
			(layer "F.Fab")
		)
		(fp_line
			(start 0.120396 0.2794)
			(end -0.12065 0.2794)
			(stroke
				(width 0.1)
				(type default)
			)
			(layer "F.Fab")
		)
		(fp_line
			(start 0.120396 0.3048)
			(end 0.120396 0.2794)
			(stroke
				(width 0.1)
				(type default)
			)
			(layer "F.Fab")
		)
		(fp_line
			(start 0.12065 -0.3048)
			(end 0.67945 -0.3048)
			(stroke
				(width 0.1)
				(type default)
			)
			(layer "F.Fab")
		)
		(fp_line
			(start 0.12065 -0.2794)
			(end 0.12065 -0.3048)
			(stroke
				(width 0.1)
				(type default)
			)
			(layer "F.Fab")
		)
		(fp_line
			(start 0.67945 -0.3048)
			(end 0.67945 0.3048)
			(stroke
				(width 0.1)
				(type default)
			)
			(layer "F.Fab")
		)
		(fp_line
			(start 0.67945 0.3048)
			(end 0.120396 0.3048)
			(stroke
				(width 0.1)
				(type default)
			)
			(layer "F.Fab")
		)
		(pad "1" smd circle
			(at -0.40005 0)
			(size 0 0)
			(layers "F.Cu" "F.Mask" "F.Paste")
			(net "P3V3_AUX")
		)
		(pad "2" smd circle
			(at 0.40005 0)
			(size 0 0)
			(layers "F.Cu" "F.Mask" "F.Paste")
			(net "GND")
		)
	)
)
